(kicad_pcb
	(version 20241229)
	(generator "pcbnew")
	(generator_version "9.0")
	(general
		(thickness 1.599998)
		(legacy_teardrops no)
	)
	(paper "A4")
	(title_block
		(title "Artix - Datacenter Secure Control Module (DC-SCM)")
		(date "2024-11-06")
		(rev "1.1.3")
		(comment 9 "footprints 527-532 of 544")
	)
	(layers
		(0 "F.Cu" signal)
		(4 "In1.Cu" signal)
		(6 "In2.Cu" signal)
		(8 "In3.Cu" signal)
		(10 "In4.Cu" signal)
		(12 "In5.Cu" signal)
		(14 "In6.Cu" signal)
		(2 "B.Cu" signal)
		(9 "F.Adhes" user "F.Adhesive")
		(11 "B.Adhes" user "B.Adhesive")
		(13 "F.Paste" user)
		(15 "B.Paste" user)
		(5 "F.SilkS" user "F.Silkscreen")
		(7 "B.SilkS" user "B.Silkscreen")
		(1 "F.Mask" user)
		(3 "B.Mask" user)
		(17 "Dwgs.User" user "User.Drawings")
		(19 "Cmts.User" user "User.Comments")
		(21 "Eco1.User" user "User.Eco1")
		(23 "Eco2.User" user "User.Eco2")
		(25 "Edge.Cuts" user)
		(27 "Margin" user)
		(31 "F.CrtYd" user "F.Courtyard")
		(29 "B.CrtYd" user "B.Courtyard")
		(35 "F.Fab" user)
		(33 "B.Fab" user)
	)
	(footprint "antmicro-footprints:R_0402_1005Metric"
		(layer "B.Cu")
		(at 117.54 152.665)
		(descr "Resistor SMD 0402")
		(tags "resistor SMD 0402")
		(property "Reference" "R116"
			(at 0.805 0.425 0)
			(layer "B.SilkS")
			(effects
				(font
					(size 0.7 0.7)
					(thickness 0.15)
				)
				(justify right bottom mirror)
			)
		)
		(property "Value" "R_0R_0402"
			(at 0 -1.4 0)
			(layer "B.Fab")
			(effects
				(font
					(size 0.7 0.7)
					(thickness 0.15)
				)
				(justify right bottom mirror)
			)
		)
		(property "Datasheet" "https://industrial.panasonic.com/cdbs/www-data/pdf/RDA0000/AOA0000C301.pdf"
			(at 0 0 0)
			(layer "F.Fab")
			(hide yes)
			(effects
				(font
					(size 1.27 1.27)
					(thickness 0.15)
				)
			)
		)
		(property "Description" "SMD Chip Resistor, Jumper, 0 ohm, 100 mW, 0402 [1005 Metric], Thick Film, General Purpose"
			(at 0 0 0)
			(layer "F.Fab")
			(hide yes)
			(effects
				(font
					(size 1.27 1.27)
					(thickness 0.15)
				)
			)
		)
		(property "Author" "Antmicro"
			(at 0 0 0)
			(layer "B.Fab")
			(hide yes)
			(effects
				(font
					(size 1 1)
					(thickness 0.15)
				)
				(justify mirror)
			)
		)
		(property "Current" "1A"
			(at 0 0 0)
			(layer "B.Fab")
			(hide yes)
			(effects
				(font
					(size 1 1)
					(thickness 0.15)
				)
				(justify mirror)
			)
		)
		(property "License" "Apache-2.0"
			(at 0 0 0)
			(layer "B.Fab")
			(hide yes)
			(effects
				(font
					(size 1 1)
					(thickness 0.15)
				)
				(justify mirror)
			)
		)
		(property "MPN" "ERJ2GE0R00X"
			(at 0 0 0)
			(layer "B.Fab")
			(hide yes)
			(effects
				(font
					(size 1 1)
					(thickness 0.15)
				)
				(justify mirror)
			)
		)
		(property "Manufacturer" "Panasonic"
			(at 0 0 0)
			(layer "B.Fab")
			(hide yes)
			(effects
				(font
					(size 1 1)
					(thickness 0.15)
				)
				(justify mirror)
			)
		)
		(property "Tolerance" "~"
			(at 0 0 0)
			(layer "B.Fab")
			(hide yes)
			(effects
				(font
					(size 1 1)
					(thickness 0.15)
				)
				(justify mirror)
			)
		)
		(property "Val" "0R"
			(at 0 0 0)
			(layer "B.Fab")
			(hide yes)
			(effects
				(font
					(size 1 1)
					(thickness 0.15)
				)
				(justify mirror)
			)
		)
		(sheetname "/Edge connector/")
		(sheetfile "edge-connector.kicad_sch")
		(attr smd)
		(fp_rect
			(start -0.925 0.47)
			(end 0.925 -0.47)
			(stroke
				(width 0.05)
				(type default)
			)
			(fill no)
			(layer "B.CrtYd")
		)
		(fp_rect
			(start -0.5 0.25)
			(end 0.5 -0.25)
			(stroke
				(width 0.15)
				(type solid)
			)
			(fill no)
			(layer "B.Fab")
		)
		(pad "1" smd roundrect
			(at -0.48 0)
			(size 0.59 0.64)
			(layers "B.Cu" "B.Mask" "B.Paste")
			(roundrect_rratio 0.25)
			(net 585 "HPM_STBY_EN_R")
			(pintype "passive")
		)
		(pad "2" smd roundrect
			(at 0.48 0)
			(size 0.59 0.64)
			(layers "B.Cu" "B.Mask" "B.Paste")
			(roundrect_rratio 0.25)
			(net 256 "/Edge connector/HPM_STBY_EN")
			(pintype "passive")
		)
	)
	(footprint "antmicro-footprints:R_0402_1005Metric"
		(layer "B.Cu")
		(at 117.54 153.665)
		(descr "Resistor SMD 0402")
		(tags "resistor SMD 0402")
		(property "Reference" "R154"
			(at 0.805 0.425 0)
			(layer "B.SilkS")
			(effects
				(font
					(size 0.7 0.7)
					(thickness 0.15)
				)
				(justify right bottom mirror)
			)
		)
		(property "Value" "R_0R_0402"
			(at 0 -1.4 0)
			(layer "B.Fab")
			(effects
				(font
					(size 0.7 0.7)
					(thickness 0.15)
				)
				(justify right bottom mirror)
			)
		)
		(property "Datasheet" "https://industrial.panasonic.com/cdbs/www-data/pdf/RDA0000/AOA0000C301.pdf"
			(at 0 0 0)
			(layer "F.Fab")
			(hide yes)
			(effects
				(font
					(size 1.27 1.27)
					(thickness 0.15)
				)
			)
		)
		(property "Description" "SMD Chip Resistor, Jumper, 0 ohm, 100 mW, 0402 [1005 Metric], Thick Film, General Purpose"
			(at 0 0 0)
			(layer "F.Fab")
			(hide yes)
			(effects
				(font
					(size 1.27 1.27)
					(thickness 0.15)
				)
			)
		)
		(property "Author" "Antmicro"
			(at 0 0 0)
			(layer "B.Fab")
			(hide yes)
			(effects
				(font
					(size 1 1)
					(thickness 0.15)
				)
				(justify mirror)
			)
		)
		(property "Current" "1A"
			(at 0 0 0)
			(layer "B.Fab")
			(hide yes)
			(effects
				(font
					(size 1 1)
					(thickness 0.15)
				)
				(justify mirror)
			)
		)
		(property "License" "Apache-2.0"
			(at 0 0 0)
			(layer "B.Fab")
			(hide yes)
			(effects
				(font
					(size 1 1)
					(thickness 0.15)
				)
				(justify mirror)
			)
		)
		(property "MPN" "ERJ2GE0R00X"
			(at 0 0 0)
			(layer "B.Fab")
			(hide yes)
			(effects
				(font
					(size 1 1)
					(thickness 0.15)
				)
				(justify mirror)
			)
		)
		(property "Manufacturer" "Panasonic"
			(at 0 0 0)
			(layer "B.Fab")
			(hide yes)
			(effects
				(font
					(size 1 1)
					(thickness 0.15)
				)
				(justify mirror)
			)
		)
		(property "Tolerance" "~"
			(at 0 0 0)
			(layer "B.Fab")
			(hide yes)
			(effects
				(font
					(size 1 1)
					(thickness 0.15)
				)
				(justify mirror)
			)
		)
		(property "Val" "0R"
			(at 0 0 0)
			(layer "B.Fab")
			(hide yes)
			(effects
				(font
					(size 1 1)
					(thickness 0.15)
				)
				(justify mirror)
			)
		)
		(sheetname "/Edge connector/")
		(sheetfile "edge-connector.kicad_sch")
		(attr smd)
		(fp_rect
			(start -0.925 0.47)
			(end 0.925 -0.47)
			(stroke
				(width 0.05)
				(type default)
			)
			(fill no)
			(layer "B.CrtYd")
		)
		(fp_rect
			(start -0.5 0.25)
			(end 0.5 -0.25)
			(stroke
				(width 0.15)
				(type solid)
			)
			(fill no)
			(layer "B.Fab")
		)
		(pad "1" smd roundrect
			(at -0.48 0)
			(size 0.59 0.64)
			(layers "B.Cu" "B.Mask" "B.Paste")
			(roundrect_rratio 0.25)
			(net 586 "HPM_STBY_RDY_R")
			(pintype "passive")
		)
		(pad "2" smd roundrect
			(at 0.48 0)
			(size 0.59 0.64)
			(layers "B.Cu" "B.Mask" "B.Paste")
			(roundrect_rratio 0.25)
			(net 257 "/Edge connector/HPM_STBY_RDY")
			(pintype "passive")
		)
	)
	(footprint "antmicro-footprints:R_0402_1005Metric"
		(layer "B.Cu")
		(at 117.54 154.665)
		(descr "Resistor SMD 0402")
		(tags "resistor SMD 0402")
		(property "Reference" "R101"
			(at 0.805 0.425 0)
			(layer "B.SilkS")
			(effects
				(font
					(size 0.7 0.7)
					(thickness 0.15)
				)
				(justify right bottom mirror)
			)
		)
		(property "Value" "R_0R_0402"
			(at 0 -1.4 0)
			(layer "B.Fab")
			(effects
				(font
					(size 0.7 0.7)
					(thickness 0.15)
				)
				(justify right bottom mirror)
			)
		)
		(property "Datasheet" "https://industrial.panasonic.com/cdbs/www-data/pdf/RDA0000/AOA0000C301.pdf"
			(at 0 0 0)
			(layer "F.Fab")
			(hide yes)
			(effects
				(font
					(size 1.27 1.27)
					(thickness 0.15)
				)
			)
		)
		(property "Description" "SMD Chip Resistor, Jumper, 0 ohm, 100 mW, 0402 [1005 Metric], Thick Film, General Purpose"
			(at 0 0 0)
			(layer "F.Fab")
			(hide yes)
			(effects
				(font
					(size 1.27 1.27)
					(thickness 0.15)
				)
			)
		)
		(property "Author" "Antmicro"
			(at 0 0 0)
			(layer "B.Fab")
			(hide yes)
			(effects
				(font
					(size 1 1)
					(thickness 0.15)
				)
				(justify mirror)
			)
		)
		(property "Current" "1A"
			(at 0 0 0)
			(layer "B.Fab")
			(hide yes)
			(effects
				(font
					(size 1 1)
					(thickness 0.15)
				)
				(justify mirror)
			)
		)
		(property "License" "Apache-2.0"
			(at 0 0 0)
			(layer "B.Fab")
			(hide yes)
			(effects
				(font
					(size 1 1)
					(thickness 0.15)
				)
				(justify mirror)
			)
		)
		(property "MPN" "ERJ2GE0R00X"
			(at 0 0 0)
			(layer "B.Fab")
			(hide yes)
			(effects
				(font
					(size 1 1)
					(thickness 0.15)
				)
				(justify mirror)
			)
		)
		(property "Manufacturer" "Panasonic"
			(at 0 0 0)
			(layer "B.Fab")
			(hide yes)
			(effects
				(font
					(size 1 1)
					(thickness 0.15)
				)
				(justify mirror)
			)
		)
		(property "Tolerance" "~"
			(at 0 0 0)
			(layer "B.Fab")
			(hide yes)
			(effects
				(font
					(size 1 1)
					(thickness 0.15)
				)
				(justify mirror)
			)
		)
		(property "Val" "0R"
			(at 0 0 0)
			(layer "B.Fab")
			(hide yes)
			(effects
				(font
					(size 1 1)
					(thickness 0.15)
				)
				(justify mirror)
			)
		)
		(sheetname "/Edge connector/")
		(sheetfile "edge-connector.kicad_sch")
		(attr smd)
		(fp_rect
			(start -0.925 0.47)
			(end 0.925 -0.47)
			(stroke
				(width 0.05)
				(type default)
			)
			(fill no)
			(layer "B.CrtYd")
		)
		(fp_rect
			(start -0.5 0.25)
			(end 0.5 -0.25)
			(stroke
				(width 0.15)
				(type solid)
			)
			(fill no)
			(layer "B.Fab")
		)
		(pad "1" smd roundrect
			(at -0.48 0)
			(size 0.59 0.64)
			(layers "B.Cu" "B.Mask" "B.Paste")
			(roundrect_rratio 0.25)
			(net 387 "HPM_FW_RECOVERY_R")
			(pintype "passive")
		)
		(pad "2" smd roundrect
			(at 0.48 0)
			(size 0.59 0.64)
			(layers "B.Cu" "B.Mask" "B.Paste")
			(roundrect_rratio 0.25)
			(net 258 "/Edge connector/HPM_FW_RECOVERY")
			(pintype "passive")
		)
	)
	(footprint "antmicro-footprints:R_0402_1005Metric"
		(layer "B.Cu")
		(at 117.545 150.675)
		(descr "Resistor SMD 0402")
		(tags "resistor SMD 0402")
		(property "Reference" "R103"
			(at 0.805 0.425 0)
			(layer "B.SilkS")
			(effects
				(font
					(size 0.7 0.7)
					(thickness 0.15)
				)
				(justify right bottom mirror)
			)
		)
		(property "Value" "R_0R_0402"
			(at 0 -1.4 0)
			(layer "B.Fab")
			(effects
				(font
					(size 0.7 0.7)
					(thickness 0.15)
				)
				(justify right bottom mirror)
			)
		)
		(property "Datasheet" "https://industrial.panasonic.com/cdbs/www-data/pdf/RDA0000/AOA0000C301.pdf"
			(at 0 0 0)
			(layer "F.Fab")
			(hide yes)
			(effects
				(font
					(size 1.27 1.27)
					(thickness 0.15)
				)
			)
		)
		(property "Description" "SMD Chip Resistor, Jumper, 0 ohm, 100 mW, 0402 [1005 Metric], Thick Film, General Purpose"
			(at 0 0 0)
			(layer "F.Fab")
			(hide yes)
			(effects
				(font
					(size 1.27 1.27)
					(thickness 0.15)
				)
			)
		)
		(property "Author" "Antmicro"
			(at 0 0 0)
			(layer "B.Fab")
			(hide yes)
			(effects
				(font
					(size 1 1)
					(thickness 0.15)
				)
				(justify mirror)
			)
		)
		(property "Current" "1A"
			(at 0 0 0)
			(layer "B.Fab")
			(hide yes)
			(effects
				(font
					(size 1 1)
					(thickness 0.15)
				)
				(justify mirror)
			)
		)
		(property "License" "Apache-2.0"
			(at 0 0 0)
			(layer "B.Fab")
			(hide yes)
			(effects
				(font
					(size 1 1)
					(thickness 0.15)
				)
				(justify mirror)
			)
		)
		(property "MPN" "ERJ2GE0R00X"
			(at 0 0 0)
			(layer "B.Fab")
			(hide yes)
			(effects
				(font
					(size 1 1)
					(thickness 0.15)
				)
				(justify mirror)
			)
		)
		(property "Manufacturer" "Panasonic"
			(at 0 0 0)
			(layer "B.Fab")
			(hide yes)
			(effects
				(font
					(size 1 1)
					(thickness 0.15)
				)
				(justify mirror)
			)
		)
		(property "Tolerance" "~"
			(at 0 0 0)
			(layer "B.Fab")
			(hide yes)
			(effects
				(font
					(size 1 1)
					(thickness 0.15)
				)
				(justify mirror)
			)
		)
		(property "Val" "0R"
			(at 0 0 0)
			(layer "B.Fab")
			(hide yes)
			(effects
				(font
					(size 1 1)
					(thickness 0.15)
				)
				(justify mirror)
			)
		)
		(sheetname "/Edge connector/")
		(sheetfile "edge-connector.kicad_sch")
		(attr smd)
		(fp_rect
			(start -0.925 0.47)
			(end 0.925 -0.47)
			(stroke
				(width 0.05)
				(type default)
			)
			(fill no)
			(layer "B.CrtYd")
		)
		(fp_rect
			(start -0.5 0.25)
			(end 0.5 -0.25)
			(stroke
				(width 0.15)
				(type solid)
			)
			(fill no)
			(layer "B.Fab")
		)
		(pad "1" smd roundrect
			(at -0.48 0)
			(size 0.59 0.64)
			(layers "B.Cu" "B.Mask" "B.Paste")
			(roundrect_rratio 0.25)
			(net 389 "SYS_PWRBTN_N_R")
			(pintype "passive")
		)
		(pad "2" smd roundrect
			(at 0.48 0)
			(size 0.59 0.64)
			(layers "B.Cu" "B.Mask" "B.Paste")
			(roundrect_rratio 0.25)
			(net 254 "/Edge connector/SYS_PWRBTN_N")
			(pintype "passive")
		)
	)
	(footprint "antmicro-footprints:R_0402_1005Metric"
		(layer "B.Cu")
		(at 117.545 151.675)
		(descr "Resistor SMD 0402")
		(tags "resistor SMD 0402")
		(property "Reference" "R102"
			(at 0.805 0.425 0)
			(layer "B.SilkS")
			(effects
				(font
					(size 0.7 0.7)
					(thickness 0.15)
				)
				(justify right bottom mirror)
			)
		)
		(property "Value" "R_0R_0402"
			(at 0 -1.4 0)
			(layer "B.Fab")
			(effects
				(font
					(size 0.7 0.7)
					(thickness 0.15)
				)
				(justify right bottom mirror)
			)
		)
		(property "Datasheet" "https://industrial.panasonic.com/cdbs/www-data/pdf/RDA0000/AOA0000C301.pdf"
			(at 0 0 0)
			(layer "F.Fab")
			(hide yes)
			(effects
				(font
					(size 1.27 1.27)
					(thickness 0.15)
				)
			)
		)
		(property "Description" "SMD Chip Resistor, Jumper, 0 ohm, 100 mW, 0402 [1005 Metric], Thick Film, General Purpose"
			(at 0 0 0)
			(layer "F.Fab")
			(hide yes)
			(effects
				(font
					(size 1.27 1.27)
					(thickness 0.15)
				)
			)
		)
		(property "Author" "Antmicro"
			(at 0 0 0)
			(layer "B.Fab")
			(hide yes)
			(effects
				(font
					(size 1 1)
					(thickness 0.15)
				)
				(justify mirror)
			)
		)
		(property "Current" "1A"
			(at 0 0 0)
			(layer "B.Fab")
			(hide yes)
			(effects
				(font
					(size 1 1)
					(thickness 0.15)
				)
				(justify mirror)
			)
		)
		(property "License" "Apache-2.0"
			(at 0 0 0)
			(layer "B.Fab")
			(hide yes)
			(effects
				(font
					(size 1 1)
					(thickness 0.15)
				)
				(justify mirror)
			)
		)
		(property "MPN" "ERJ2GE0R00X"
			(at 0 0 0)
			(layer "B.Fab")
			(hide yes)
			(effects
				(font
					(size 1 1)
					(thickness 0.15)
				)
				(justify mirror)
			)
		)
		(property "Manufacturer" "Panasonic"
			(at 0 0 0)
			(layer "B.Fab")
			(hide yes)
			(effects
				(font
					(size 1 1)
					(thickness 0.15)
				)
				(justify mirror)
			)
		)
		(property "Tolerance" "~"
			(at 0 0 0)
			(layer "B.Fab")
			(hide yes)
			(effects
				(font
					(size 1 1)
					(thickness 0.15)
				)
				(justify mirror)
			)
		)
		(property "Val" "0R"
			(at 0 0 0)
			(layer "B.Fab")
			(hide yes)
			(effects
				(font
					(size 1 1)
					(thickness 0.15)
				)
				(justify mirror)
			)
		)
		(sheetname "/Edge connector/")
		(sheetfile "edge-connector.kicad_sch")
		(attr smd)
		(fp_rect
			(start -0.925 0.47)
			(end 0.925 -0.47)
			(stroke
				(width 0.05)
				(type default)
			)
			(fill no)
			(layer "B.CrtYd")
		)
		(fp_rect
			(start -0.5 0.25)
			(end 0.5 -0.25)
			(stroke
				(width 0.15)
				(type solid)
			)
			(fill no)
			(layer "B.Fab")
		)
		(pad "1" smd roundrect
			(at -0.48 0)
			(size 0.59 0.64)
			(layers "B.Cu" "B.Mask" "B.Paste")
			(roundrect_rratio 0.25)
			(net 388 "HPM_STBY_RST_N_R")
			(pintype "passive")
		)
		(pad "2" smd roundrect
			(at 0.48 0)
			(size 0.59 0.64)
			(layers "B.Cu" "B.Mask" "B.Paste")
			(roundrect_rratio 0.25)
			(net 255 "/Edge connector/HPM_STBY_RST_N")
			(pintype "passive")
		)
	)
	(footprint "antmicro-footprints:R_0402_1005Metric"
		(layer "B.Cu")
		(at 117.495 142.675 180)
		(descr "Resistor SMD 0402")
		(tags "resistor SMD 0402")
		(property "Reference" "R111"
			(at -0.805 -0.425 0)
			(layer "B.SilkS")
			(effects
				(font
					(size 0.7 0.7)
					(thickness 0.15)
				)
				(justify right bottom mirror)
			)
		)
		(property "Value" "R_0R_0402"
			(at 0 -1.4 0)
			(layer "B.Fab")
			(effects
				(font
					(size 0.7 0.7)
					(thickness 0.15)
				)
				(justify left bottom mirror)
			)
		)
		(property "Datasheet" "https://industrial.panasonic.com/cdbs/www-data/pdf/RDA0000/AOA0000C301.pdf"
			(at 0 0 180)
			(layer "F.Fab")
			(hide yes)
			(effects
				(font
					(size 1.27 1.27)
					(thickness 0.15)
				)
			)
		)
		(property "Description" "SMD Chip Resistor, Jumper, 0 ohm, 100 mW, 0402 [1005 Metric], Thick Film, General Purpose"
			(at 0 0 180)
			(layer "F.Fab")
			(hide yes)
			(effects
				(font
					(size 1.27 1.27)
					(thickness 0.15)
				)
			)
		)
		(property "Author" "Antmicro"
			(at 234.99 285.35 0)
			(layer "B.Fab")
			(hide yes)
			(effects
				(font
					(size 1 1)
					(thickness 0.15)
				)
				(justify mirror)
			)
		)
		(property "Current" "1A"
			(at 234.99 285.35 0)
			(layer "B.Fab")
			(hide yes)
			(effects
				(font
					(size 1 1)
					(thickness 0.15)
				)
				(justify mirror)
			)
		)
		(property "License" "Apache-2.0"
			(at 234.99 285.35 0)
			(layer "B.Fab")
			(hide yes)
			(effects
				(font
					(size 1 1)
					(thickness 0.15)
				)
				(justify mirror)
			)
		)
		(property "MPN" "ERJ2GE0R00X"
			(at 234.99 285.35 0)
			(layer "B.Fab")
			(hide yes)
			(effects
				(font
					(size 1 1)
					(thickness 0.15)
				)
				(justify mirror)
			)
		)
		(property "Manufacturer" "Panasonic"
			(at 234.99 285.35 0)
			(layer "B.Fab")
			(hide yes)
			(effects
				(font
					(size 1 1)
					(thickness 0.15)
				)
				(justify mirror)
			)
		)
		(property "Tolerance" "~"
			(at 234.99 285.35 0)
			(layer "B.Fab")
			(hide yes)
			(effects
				(font
					(size 1 1)
					(thickness 0.15)
				)
				(justify mirror)
			)
		)
		(property "Val" "0R"
			(at 234.99 285.35 0)
			(layer "B.Fab")
			(hide yes)
			(effects
				(font
					(size 1 1)
					(thickness 0.15)
				)
				(justify mirror)
			)
		)
		(sheetname "/Edge connector/")
		(sheetfile "edge-connector.kicad_sch")
		(attr smd)
		(fp_rect
			(start -0.925 0.47)
			(end 0.925 -0.47)
			(stroke
				(width 0.05)
				(type default)
			)
			(fill no)
			(layer "B.CrtYd")
		)
		(fp_rect
			(start -0.5 0.25)
			(end 0.5 -0.25)
			(stroke
				(width 0.15)
				(type solid)
			)
			(fill no)
			(layer "B.Fab")
		)
		(pad "1" smd roundrect
			(at -0.48 0 180)
			(size 0.59 0.64)
			(layers "B.Cu" "B.Mask" "B.Paste")
			(roundrect_rratio 0.25)
			(net 246 "/Edge connector/SPARE0")
			(pintype "passive")
		)
		(pad "2" smd roundrect
			(at 0.48 0 180)
			(size 0.59 0.64)
			(layers "B.Cu" "B.Mask" "B.Paste")
			(roundrect_rratio 0.25)
			(net 397 "SPARE0_R")
			(pintype "passive")
		)
	)
)
